;EXTENTS: -5.000  -20.000 47.000  37.000  
;LEADER: 12 
;HEADER: 
;CODE  : ASCII 
;FILE  : G:/<user>/F0T/9054_F0T_PDB_BD_GPU_F/Board/TO/TO/12152022_DAF0TPB1AF0_F0T_PDB_BD_GPU_F_artwork/9054_F0T_PDB_BD_GPU_F_V04_1213_1550_1-10.rou for board G:/<user>/F0T/9054_F0T_PDB_BD_GPU_F/Board/TO/TO/12152022_DAF0TPB1AF0_F0T_PDB_BD_GPU_F_artwork/#Taaaacg03704.tmp, layers TOP to BOTTOM
%
G90
F1
M16
T01
M16
G00X1833289Y0099212
G40
M15
G01X1838189Y0099212
M16
G00X1833288Y0481693
G40
M15
G01X1838188Y0481693
M16
G40
M30
